(kicad_pcb
	(version 20260206)
	(generator "pcbnew")
	(generator_version "10.0")
	(general
		(thickness 1.6)
		(legacy_teardrops no)
	)
	(paper "A4")
	(title_block
		(title "timecard-production-celestica-r4006 — R4006-B0001-02_R01.brd")
		(comment 1 "Time Appliance Project (Time Card) / footprints 778-783 of 1113")
	)
	(layers
		(0 "F.Cu" signal "TOP")
		(4 "In1.Cu" signal "L02_GND1")
		(6 "In2.Cu" signal "L03_SIG1")
		(8 "In3.Cu" signal "L04_GND2")
		(10 "In4.Cu" signal "L05_VCC1")
		(12 "In5.Cu" signal "L06_VCC2")
		(14 "In6.Cu" signal "L07_GND3")
		(16 "In7.Cu" signal "L08_SIG2")
		(18 "In8.Cu" signal "L09_GND4")
		(2 "B.Cu" signal "BOTTOM")
		(9 "F.Adhes" user "F.Adhesive")
		(11 "B.Adhes" user "B.Adhesive")
		(13 "F.Paste" user "Package Geometry/Pastemask Top")
		(15 "B.Paste" user "Package Geometry/Pastemask Bottom")
		(5 "F.SilkS" user "Ref Des/Silkscreen Top")
		(7 "B.SilkS" user "Ref Des/Silkscreen Bottom")
		(1 "F.Mask" user "Board Geometry/Soldermask Top")
		(3 "B.Mask" user "Board Geometry/Soldermask Bottom")
		(17 "Dwgs.User" user "User.Drawings")
		(19 "Cmts.User" user "User.Comments")
		(21 "Eco1.User" user "User.Eco1")
		(23 "Eco2.User" user "User.Eco2")
		(25 "Edge.Cuts" user "Board Geometry/Outline")
		(27 "Margin" user)
		(31 "F.CrtYd" user "Package Geometry/Place Bound Top")
		(29 "B.CrtYd" user "Package Geometry/Place Bound Bottom")
		(35 "F.Fab" user "Ref Des/Assembly Top")
		(33 "B.Fab" user "Ref Des/Assembly Bottom")
	)
	(footprint ""
		(layer "B.Cu")
		(at 105.347262 -51.823112 180)
		(property "Reference" "C112"
			(at -0.824738 0.977138 0)
			(unlocked yes)
			(layer "B.SilkS")
			(effects
				(font
					(size 0.635 0.4064)
					(thickness 0.1524)
				)
				(justify mirror)
			)
		)
		(property "Value" "VAL*"
			(at 0 3.718306 180)
			(unlocked yes)
			(layer "B.Fab")
			(hide yes)
			(effects
				(font
					(size 0.7874 0.5842)
					(thickness 0.127)
				)
				(justify mirror)
			)
		)
		(property "Device Type" "CAPACITOR-G105-0B104-CK,0.1UF,A"
			(at 0 1.432306 180)
			(unlocked yes)
			(layer "B.Fab")
			(hide yes)
			(effects
				(font
					(size 0.7874 0.5842)
					(thickness 0.127)
				)
				(justify mirror)
			)
		)
		(property "User Part Number" "PARTNUM*"
			(at 0 2.575306 180)
			(unlocked yes)
			(layer "Cmts.User")
			(hide yes)
			(effects
				(font
					(size 0.7874 0.5842)
					(thickness 0.127)
				)
				(justify mirror)
			)
		)
		(property "Tolerance" "TOL*"
			(at 0 4.861306 180)
			(unlocked yes)
			(layer "Cmts.User")
			(hide yes)
			(effects
				(font
					(size 0.7874 0.5842)
					(thickness 0.127)
				)
				(justify mirror)
			)
		)
		(duplicate_pad_numbers_are_jumpers no)
		(fp_line
			(start 0.970026 0.4699)
			(end 0.970026 -0.4699)
			(stroke
				(width 0.1)
				(type default)
			)
			(layer "B.SilkS")
		)
		(fp_line
			(start 0.970026 -0.4699)
			(end -0.970026 -0.4699)
			(stroke
				(width 0.1)
				(type default)
			)
			(layer "B.SilkS")
		)
		(fp_line
			(start -0.970026 0.4699)
			(end 0.970026 0.4699)
			(stroke
				(width 0.1)
				(type default)
			)
			(layer "B.SilkS")
		)
		(fp_line
			(start -0.970026 -0.4699)
			(end -0.970026 0.4699)
			(stroke
				(width 0.1)
				(type default)
			)
			(layer "B.SilkS")
		)
		(fp_poly
			(pts
				(xy 0.970026 0.4699) (xy -0.970026 0.4699) (xy -0.970026 -0.4699) (xy 0.970026 -0.4699)
			)
			(stroke
				(width 0)
				(type default)
			)
			(fill no)
			(layer "B.CrtYd")
		)
		(fp_line
			(start 0.508 0.3048)
			(end 0.508 -0.3048)
			(stroke
				(width 0.1)
				(type default)
			)
			(layer "B.Fab")
		)
		(fp_line
			(start 0.508 -0.3048)
			(end -0.508 -0.3048)
			(stroke
				(width 0.1)
				(type default)
			)
			(layer "B.Fab")
		)
		(fp_line
			(start -0.508 0.3048)
			(end 0.508 0.3048)
			(stroke
				(width 0.1)
				(type default)
			)
			(layer "B.Fab")
		)
		(fp_line
			(start -0.508 -0.3048)
			(end -0.508 0.3048)
			(stroke
				(width 0.1)
				(type default)
			)
			(layer "B.Fab")
		)
		(pad "1" smd circle
			(at 0.500126 0)
			(size 0.635 0.635)
			(layers "B.Cu" "B.Mask" "B.Paste")
			(net "XP3R3V_FPGA")
		)
		(pad "2" smd circle
			(at -0.500126 0)
			(size 0.635 0.635)
			(layers "B.Cu" "B.Mask" "B.Paste")
			(net "SG")
		)
	)
	(footprint ""
		(layer "B.Cu")
		(at 110.49 -61.976 -90)
		(property "Reference" "R207"
			(at -3.81 0.03937 270)
			(unlocked yes)
			(layer "B.SilkS")
			(effects
				(font
					(size 0.7874 0.5842)
					(thickness 0.1524)
				)
				(justify mirror)
			)
		)
		(property "Value" "VAL*"
			(at -0.02032 2.13233 270)
			(unlocked yes)
			(layer "B.Fab")
			(hide yes)
			(effects
				(font
					(size 0.7874 0.5842)
					(thickness 0.1524)
				)
				(justify mirror)
			)
		)
		(property "Device Type" "RESISTOR-G155-149R9-01,49.9OHMA"
			(at -0.008382 1.210564 270)
			(unlocked yes)
			(layer "B.Fab")
			(hide yes)
			(effects
				(font
					(size 0.7874 0.5842)
					(thickness 0.1524)
				)
				(justify mirror)
			)
		)
		(property "User Part Number" "PARTNUM*"
			(at -0.02032 4.024884 270)
			(unlocked yes)
			(layer "Cmts.User")
			(hide yes)
			(effects
				(font
					(size 0.7874 0.5842)
					(thickness 0.1524)
				)
				(justify mirror)
			)
		)
		(property "Tolerance" "TOL*"
			(at -0.044704 3.05435 270)
			(unlocked yes)
			(layer "Cmts.User")
			(hide yes)
			(effects
				(font
					(size 0.7874 0.5842)
					(thickness 0.1524)
				)
				(justify mirror)
			)
		)
		(duplicate_pad_numbers_are_jumpers no)
		(fp_line
			(start -1.143 0.5588)
			(end -1.143 -0.5588)
			(stroke
				(width 0.1)
				(type default)
			)
			(layer "B.SilkS")
		)
		(fp_line
			(start 1.143 0.5588)
			(end -1.143 0.5588)
			(stroke
				(width 0.1)
				(type default)
			)
			(layer "B.SilkS")
		)
		(fp_line
			(start -1.143 -0.5588)
			(end 1.143 -0.5588)
			(stroke
				(width 0.1)
				(type default)
			)
			(layer "B.SilkS")
		)
		(fp_line
			(start 1.143 -0.5588)
			(end 1.143 0.5588)
			(stroke
				(width 0.1)
				(type default)
			)
			(layer "B.SilkS")
		)
		(fp_rect
			(start -1.143 0.5588)
			(end 1.143 -0.5588)
			(stroke
				(width 0)
				(type default)
			)
			(fill no)
			(layer "B.CrtYd")
		)
		(fp_line
			(start -0.508 0.3048)
			(end -0.508 -0.3048)
			(stroke
				(width 0.1)
				(type default)
			)
			(layer "B.Fab")
		)
		(fp_line
			(start 0.508 0.3048)
			(end -0.508 0.3048)
			(stroke
				(width 0.1)
				(type default)
			)
			(layer "B.Fab")
		)
		(fp_line
			(start -0.508 -0.3048)
			(end 0.508 -0.3048)
			(stroke
				(width 0.1)
				(type default)
			)
			(layer "B.Fab")
		)
		(fp_line
			(start 0.508 -0.3048)
			(end 0.508 0.3048)
			(stroke
				(width 0.1)
				(type default)
			)
			(layer "B.Fab")
		)
		(pad "1" smd rect
			(at 0.5334 0 90)
			(size 0.7112 0.6096)
			(layers "B.Cu" "B.Mask" "B.Paste")
			(net "CCLK_0")
		)
		(pad "2" smd rect
			(at -0.5334 0 90)
			(size 0.7112 0.6096)
			(layers "B.Cu" "B.Mask" "B.Paste")
			(net "FPGA_FLASH_CLK")
		)
		(zone
			(layer "B.Cu")
			(hatch none 0.5)
			(connect_pads
				(clearance 0)
			)
			(min_thickness 0.25)
			(keepout
				(tracks allowed)
				(vias not_allowed)
				(pads allowed)
				(copperpour not_allowed)
				(footprints allowed)
			)
			(placement
				(enabled no)
				(sheetname "")
			)
			(fill
				(thermal_gap 0.5)
				(thermal_bridge_width 0.5)
				(island_removal_mode 0)
			)
			(polygon
				(pts
					(xy 110.1852 -62.0522) (xy 110.1852 -61.8998) (xy 110.7948 -61.8998) (xy 110.7948 -62.0522)
				)
			)
		)
	)
	(footprint ""
		(layer "B.Cu")
		(at 77.089 -49.403 180)
		(property "Reference" "C64"
			(at -3.048 -0.03937 0)
			(unlocked yes)
			(layer "B.SilkS")
			(effects
				(font
					(size 0.7874 0.5842)
					(thickness 0.1524)
				)
				(justify mirror)
			)
		)
		(property "Value" "VAL*"
			(at -0.0762 3.134106 180)
			(unlocked yes)
			(layer "B.Fab")
			(hide yes)
			(effects
				(font
					(size 0.7874 0.5842)
					(thickness 0.1524)
				)
				(justify mirror)
			)
		)
		(property "Tolerance" "TOL*"
			(at -0.0762 4.048506 180)
			(unlocked yes)
			(layer "Cmts.User")
			(hide yes)
			(effects
				(font
					(size 0.7874 0.5842)
					(thickness 0.1524)
				)
				(justify mirror)
			)
		)
		(property "User Part Number" "PARTNUM*"
			(at -0.1016 5.013706 180)
			(unlocked yes)
			(layer "Cmts.User")
			(hide yes)
			(effects
				(font
					(size 0.7874 0.5842)
					(thickness 0.1524)
				)
				(justify mirror)
			)
		)
		(property "Device Type" "CAPACITOR-G107-0F106-EM,10UF,2A"
			(at -0.0508 2.194306 180)
			(unlocked yes)
			(layer "B.Fab")
			(hide yes)
			(effects
				(font
					(size 0.7874 0.5842)
					(thickness 0.1524)
				)
				(justify mirror)
			)
		)
		(duplicate_pad_numbers_are_jumpers no)
		(fp_line
			(start 1.5748 0.9398)
			(end -1.5748 0.9398)
			(stroke
				(width 0.1)
				(type default)
			)
			(layer "B.SilkS")
		)
		(fp_line
			(start 1.5748 -0.9398)
			(end 1.5748 0.9398)
			(stroke
				(width 0.1)
				(type default)
			)
			(layer "B.SilkS")
		)
		(fp_line
			(start -1.5748 0.9398)
			(end -1.5748 -0.9398)
			(stroke
				(width 0.1)
				(type default)
			)
			(layer "B.SilkS")
		)
		(fp_line
			(start -1.5748 -0.9398)
			(end 1.5748 -0.9398)
			(stroke
				(width 0.1)
				(type default)
			)
			(layer "B.SilkS")
		)
		(fp_rect
			(start 1.5748 0.9398)
			(end -1.5748 -0.9398)
			(stroke
				(width 0)
				(type default)
			)
			(fill no)
			(layer "B.CrtYd")
		)
		(fp_line
			(start 1.016 0.635)
			(end -1.016 0.635)
			(stroke
				(width 0.1)
				(type default)
			)
			(layer "B.Fab")
		)
		(fp_line
			(start 1.016 -0.635)
			(end 1.016 0.635)
			(stroke
				(width 0.1)
				(type default)
			)
			(layer "B.Fab")
		)
		(fp_line
			(start -1.016 0.635)
			(end -1.016 -0.635)
			(stroke
				(width 0.1)
				(type default)
			)
			(layer "B.Fab")
		)
		(fp_line
			(start -1.016 -0.635)
			(end 1.016 -0.635)
			(stroke
				(width 0.1)
				(type default)
			)
			(layer "B.Fab")
		)
		(pad "1" smd rect
			(at 0.8382 0)
			(size 0.9652 1.3716)
			(layers "B.Cu" "B.Mask" "B.Paste")
			(net "XP5R0V_MAC_USB")
		)
		(pad "2" smd rect
			(at -0.8382 0)
			(size 0.9652 1.3716)
			(layers "B.Cu" "B.Mask" "B.Paste")
			(net "SG")
		)
		(zone
			(layer "B.Cu")
			(hatch none 0.5)
			(connect_pads
				(clearance 0)
			)
			(min_thickness 0.25)
			(keepout
				(tracks allowed)
				(vias not_allowed)
				(pads allowed)
				(copperpour not_allowed)
				(footprints allowed)
			)
			(placement
				(enabled no)
				(sheetname "")
			)
			(fill
				(thermal_gap 0.5)
				(thermal_bridge_width 0.5)
				(island_removal_mode 0)
			)
			(polygon
				(pts
					(xy 76.8604 -50.038) (xy 76.8604 -48.768) (xy 77.3176 -48.768) (xy 77.3176 -50.038)
				)
			)
		)
	)
	(footprint ""
		(layer "B.Cu")
		(at 107.84713 -41.32326 -90)
		(property "Reference" "C166"
			(at 1.016 41.38422 270)
			(unlocked yes)
			(layer "B.SilkS")
			(effects
				(font
					(size 0.635 0.4064)
					(thickness 0.1524)
				)
				(justify mirror)
			)
		)
		(property "Value" "VAL*"
			(at 0 3.718306 270)
			(unlocked yes)
			(layer "B.Fab")
			(hide yes)
			(effects
				(font
					(size 0.7874 0.5842)
					(thickness 0.127)
				)
				(justify mirror)
			)
		)
		(property "Device Type" "CAPACITOR-G105-0B104-CK,0.1UF,A"
			(at 0 1.432306 270)
			(unlocked yes)
			(layer "B.Fab")
			(hide yes)
			(effects
				(font
					(size 0.7874 0.5842)
					(thickness 0.127)
				)
				(justify mirror)
			)
		)
		(property "User Part Number" "PARTNUM*"
			(at 0 2.575306 270)
			(unlocked yes)
			(layer "Cmts.User")
			(hide yes)
			(effects
				(font
					(size 0.7874 0.5842)
					(thickness 0.127)
				)
				(justify mirror)
			)
		)
		(property "Tolerance" "TOL*"
			(at 0 4.861306 270)
			(unlocked yes)
			(layer "Cmts.User")
			(hide yes)
			(effects
				(font
					(size 0.7874 0.5842)
					(thickness 0.127)
				)
				(justify mirror)
			)
		)
		(duplicate_pad_numbers_are_jumpers no)
		(fp_line
			(start -0.970026 0.4699)
			(end 0.970026 0.4699)
			(stroke
				(width 0.1)
				(type default)
			)
			(layer "B.SilkS")
		)
		(fp_line
			(start 0.970026 0.4699)
			(end 0.970026 -0.4699)
			(stroke
				(width 0.1)
				(type default)
			)
			(layer "B.SilkS")
		)
		(fp_line
			(start -0.970026 -0.4699)
			(end -0.970026 0.4699)
			(stroke
				(width 0.1)
				(type default)
			)
			(layer "B.SilkS")
		)
		(fp_line
			(start 0.970026 -0.4699)
			(end -0.970026 -0.4699)
			(stroke
				(width 0.1)
				(type default)
			)
			(layer "B.SilkS")
		)
		(fp_poly
			(pts
				(xy 0.970026 0.4699) (xy -0.970026 0.4699) (xy -0.970026 -0.4699) (xy 0.970026 -0.4699)
			)
			(stroke
				(width 0)
				(type default)
			)
			(fill no)
			(layer "B.CrtYd")
		)
		(fp_line
			(start -0.508 0.3048)
			(end 0.508 0.3048)
			(stroke
				(width 0.1)
				(type default)
			)
			(layer "B.Fab")
		)
		(fp_line
			(start 0.508 0.3048)
			(end 0.508 -0.3048)
			(stroke
				(width 0.1)
				(type default)
			)
			(layer "B.Fab")
		)
		(fp_line
			(start -0.508 -0.3048)
			(end -0.508 0.3048)
			(stroke
				(width 0.1)
				(type default)
			)
			(layer "B.Fab")
		)
		(fp_line
			(start 0.508 -0.3048)
			(end -0.508 -0.3048)
			(stroke
				(width 0.1)
				(type default)
			)
			(layer "B.Fab")
		)
		(pad "1" smd circle
			(at 0.500126 0 90)
			(size 0.635 0.635)
			(layers "B.Cu" "B.Mask" "B.Paste")
			(net "XP1R0V_FPGA_VCCINT")
		)
		(pad "2" smd circle
			(at -0.500126 0 90)
			(size 0.635 0.635)
			(layers "B.Cu" "B.Mask" "B.Paste")
			(net "SG")
		)
	)
	(footprint ""
		(layer "B.Cu")
		(at 102.84714 -49.323244 -90)
		(property "Reference" "C170"
			(at -2.111756 0.26289 270)
			(unlocked yes)
			(layer "B.SilkS")
			(effects
				(font
					(size 0.635 0.4064)
					(thickness 0.1524)
				)
				(justify mirror)
			)
		)
		(property "Value" "VAL*"
			(at 0 3.718306 270)
			(unlocked yes)
			(layer "B.Fab")
			(hide yes)
			(effects
				(font
					(size 0.7874 0.5842)
					(thickness 0.127)
				)
				(justify mirror)
			)
		)
		(property "Device Type" "CAPACITOR-G105-0F475-BM,4.7UF,A"
			(at 0 1.432306 270)
			(unlocked yes)
			(layer "B.Fab")
			(hide yes)
			(effects
				(font
					(size 0.7874 0.5842)
					(thickness 0.127)
				)
				(justify mirror)
			)
		)
		(property "User Part Number" "PARTNUM*"
			(at 0 2.575306 270)
			(unlocked yes)
			(layer "Cmts.User")
			(hide yes)
			(effects
				(font
					(size 0.7874 0.5842)
					(thickness 0.127)
				)
				(justify mirror)
			)
		)
		(property "Tolerance" "TOL*"
			(at 0 4.861306 270)
			(unlocked yes)
			(layer "Cmts.User")
			(hide yes)
			(effects
				(font
					(size 0.7874 0.5842)
					(thickness 0.127)
				)
				(justify mirror)
			)
		)
		(duplicate_pad_numbers_are_jumpers no)
		(fp_line
			(start -0.970026 0.4699)
			(end 0.970026 0.4699)
			(stroke
				(width 0.1)
				(type default)
			)
			(layer "B.SilkS")
		)
		(fp_line
			(start 0.970026 0.4699)
			(end 0.970026 -0.4699)
			(stroke
				(width 0.1)
				(type default)
			)
			(layer "B.SilkS")
		)
		(fp_line
			(start -0.970026 -0.4699)
			(end -0.970026 0.4699)
			(stroke
				(width 0.1)
				(type default)
			)
			(layer "B.SilkS")
		)
		(fp_line
			(start 0.970026 -0.4699)
			(end -0.970026 -0.4699)
			(stroke
				(width 0.1)
				(type default)
			)
			(layer "B.SilkS")
		)
		(fp_poly
			(pts
				(xy 0.970026 0.4699) (xy -0.970026 0.4699) (xy -0.970026 -0.4699) (xy 0.970026 -0.4699)
			)
			(stroke
				(width 0)
				(type default)
			)
			(fill no)
			(layer "B.CrtYd")
		)
		(fp_line
			(start -0.508 0.3048)
			(end 0.508 0.3048)
			(stroke
				(width 0.1)
				(type default)
			)
			(layer "B.Fab")
		)
		(fp_line
			(start 0.508 0.3048)
			(end 0.508 -0.3048)
			(stroke
				(width 0.1)
				(type default)
			)
			(layer "B.Fab")
		)
		(fp_line
			(start -0.508 -0.3048)
			(end -0.508 0.3048)
			(stroke
				(width 0.1)
				(type default)
			)
			(layer "B.Fab")
		)
		(fp_line
			(start 0.508 -0.3048)
			(end -0.508 -0.3048)
			(stroke
				(width 0.1)
				(type default)
			)
			(layer "B.Fab")
		)
		(pad "1" smd circle
			(at 0.500126 0 90)
			(size 0.635 0.635)
			(layers "B.Cu" "B.Mask" "B.Paste")
			(net "XP3R3V_FPGA")
		)
		(pad "2" smd circle
			(at -0.500126 0 90)
			(size 0.635 0.635)
			(layers "B.Cu" "B.Mask" "B.Paste")
			(net "SG")
		)
	)
	(footprint ""
		(layer "B.Cu")
		(at 16.6624 -15.621 180)
		(property "Reference" "C82"
			(at -0.2286 -1.18237 0)
			(unlocked yes)
			(layer "B.SilkS")
			(effects
				(font
					(size 0.7874 0.5842)
					(thickness 0.1524)
				)
				(justify mirror)
			)
		)
		(property "Value" "VAL*"
			(at -0.0762 2.067306 180)
			(unlocked yes)
			(layer "B.Fab")
			(hide yes)
			(effects
				(font
					(size 0.7874 0.5842)
					(thickness 0.1524)
				)
				(justify mirror)
			)
		)
		(property "Device Type" "CAPACITOR-G105-0B104-CK,0.1UF,A"
			(at -0.0508 1.127506 180)
			(unlocked yes)
			(layer "B.Fab")
			(hide yes)
			(effects
				(font
					(size 0.7874 0.5842)
					(thickness 0.1524)
				)
				(justify mirror)
			)
		)
		(property "User Part Number" "PARTNUM*"
			(at -0.1016 4.023106 180)
			(unlocked yes)
			(layer "Cmts.User")
			(hide yes)
			(effects
				(font
					(size 0.7874 0.5842)
					(thickness 0.1524)
				)
				(justify mirror)
			)
		)
		(property "Tolerance" "TOL*"
			(at -0.0762 3.032506 180)
			(unlocked yes)
			(layer "Cmts.User")
			(hide yes)
			(effects
				(font
					(size 0.7874 0.5842)
					(thickness 0.1524)
				)
				(justify mirror)
			)
		)
		(duplicate_pad_numbers_are_jumpers no)
		(fp_line
			(start 1.143 0.5588)
			(end -1.143 0.5588)
			(stroke
				(width 0.1)
				(type default)
			)
			(layer "B.SilkS")
		)
		(fp_line
			(start 1.143 -0.5588)
			(end 1.143 0.5588)
			(stroke
				(width 0.1)
				(type default)
			)
			(layer "B.SilkS")
		)
		(fp_line
			(start -1.143 0.5588)
			(end -1.143 -0.5588)
			(stroke
				(width 0.1)
				(type default)
			)
			(layer "B.SilkS")
		)
		(fp_line
			(start -1.143 -0.5588)
			(end 1.143 -0.5588)
			(stroke
				(width 0.1)
				(type default)
			)
			(layer "B.SilkS")
		)
		(fp_rect
			(start -1.143 0.5588)
			(end 1.143 -0.5588)
			(stroke
				(width 0)
				(type default)
			)
			(fill no)
			(layer "B.CrtYd")
		)
		(fp_line
			(start 0.508 0.3048)
			(end -0.508 0.3048)
			(stroke
				(width 0.1)
				(type default)
			)
			(layer "B.Fab")
		)
		(fp_line
			(start 0.508 -0.3048)
			(end 0.508 0.3048)
			(stroke
				(width 0.1)
				(type default)
			)
			(layer "B.Fab")
		)
		(fp_line
			(start -0.508 0.3048)
			(end -0.508 -0.3048)
			(stroke
				(width 0.1)
				(type default)
			)
			(layer "B.Fab")
		)
		(fp_line
			(start -0.508 -0.3048)
			(end 0.508 -0.3048)
			(stroke
				(width 0.1)
				(type default)
			)
			(layer "B.Fab")
		)
		(pad "1" smd rect
			(at 0.5334 0)
			(size 0.7112 0.6096)
			(layers "B.Cu" "B.Mask" "B.Paste")
			(net "XP3R3V_FPGA")
		)
		(pad "2" smd rect
			(at -0.5334 0)
			(size 0.7112 0.6096)
			(layers "B.Cu" "B.Mask" "B.Paste")
			(net "SG")
		)
		(zone
			(layer "B.Cu")
			(hatch none 0.5)
			(connect_pads
				(clearance 0)
			)
			(min_thickness 0.25)
			(keepout
				(tracks allowed)
				(vias not_allowed)
				(pads allowed)
				(copperpour not_allowed)
				(footprints allowed)
			)
			(placement
				(enabled no)
				(sheetname "")
			)
			(fill
				(thermal_gap 0.5)
				(thermal_bridge_width 0.5)
				(island_removal_mode 0)
			)
			(polygon
				(pts
					(xy 16.7386 -15.9258) (xy 16.5862 -15.9258) (xy 16.5862 -15.3162) (xy 16.7386 -15.3162)
				)
			)
		)
	)
)
